# T6G (Grand Teton) — schematic netlist excerpt (pin names and nets, part order shuffled) for the footprints in the layout excerpt that follows; sources: Cadence DE-HDL packaged netlist, KiCad conversion of 04192023_DAF0TMB3IC0_F0TG_MB_C_brd_V02_OCP.brd

C2596  Q_CAP  22UF 4V 20% X6S  pkg C0402  page 70 : A = PVDDCR_SOC_P0 ; B = GND
C3889  Q_CAP  22UF 4V 20% X6S  pkg C0402  page 68 : A = PVDDCR_SOC_P0 ; B = GND
C447  Q_CAP  0.1UF 10V 10% X7S  pkg C0201  page 356 : A = P1V8_CPU1_RT3_1A ; B = GND

(kicad_pcb
	(version 20260206)
	(generator "pcbnew")
	(generator_version "10.0")
	(general
		(thickness 1.6)
		(legacy_teardrops no)
	)
	(paper "A4")
	(title_block
		(title "04192023_DAF0TMB3IC0_F0TG_MB_C_brd_V02_OCP.brd")
		(comment 1 "Grand Teton / footprints 4984-4986 of 8354")
	)
	(layers
		(0 "F.Cu" signal "TOP")
		(4 "In1.Cu" signal "GND")
		(6 "In2.Cu" signal "IN1")
		(8 "In3.Cu" signal "GND1")
		(10 "In4.Cu" signal "IN2")
		(12 "In5.Cu" signal "GND2")
		(14 "In6.Cu" signal "IN3")
		(16 "In7.Cu" signal "GND3")
		(18 "In8.Cu" signal "VCC")
		(20 "In9.Cu" signal "VCC1")
		(22 "In10.Cu" signal "GND4")
		(24 "In11.Cu" signal "IN4")
		(26 "In12.Cu" signal "GND5")
		(28 "In13.Cu" signal "IN5")
		(30 "In14.Cu" signal "GND6")
		(32 "In15.Cu" signal "IN6")
		(34 "In16.Cu" signal "GND7")
		(2 "B.Cu" signal "BOTTOM")
		(9 "F.Adhes" user "F.Adhesive")
		(11 "B.Adhes" user "B.Adhesive")
		(13 "F.Paste" user "Package Geometry/Pastemask Top")
		(15 "B.Paste" user "Package Geometry/Pastemask Bottom")
		(5 "F.SilkS" user "Ref Des/Silkscreen Top")
		(7 "B.SilkS" user "Ref Des/Silkscreen Bottom")
		(1 "F.Mask" user "Board Geometry/Soldermask Top")
		(3 "B.Mask" user "Board Geometry/Soldermask Bottom")
		(17 "Dwgs.User" user "User.Drawings")
		(19 "Cmts.User" user "User.Comments")
		(21 "Eco1.User" user "User.Eco1")
		(23 "Eco2.User" user "User.Eco2")
		(25 "Edge.Cuts" user "Board Geometry/Outline")
		(27 "Margin" user)
		(31 "F.CrtYd" user "Package Geometry/Place Bound Top")
		(29 "B.CrtYd" user "Package Geometry/Place Bound Bottom")
		(35 "F.Fab" user "Ref Des/Assembly Top")
		(33 "B.Fab" user "Ref Des/Assembly Bottom")
	)
	(footprint ""
		(layer "B.Cu")
		(at 351.612454 -261.17931 180)
		(property "Reference" "C2596"
			(at 0 0 0)
			(layer "B.SilkS")
			(hide yes)
			(effects
				(font
					(size 1.27 1.27)
				)
				(justify mirror)
			)
		)
		(property "Value" ""
			(at 0 0 0)
			(layer "B.Fab")
			(effects
				(font
					(size 1.27 1.27)
				)
				(justify mirror)
			)
		)
		(duplicate_pad_numbers_are_jumpers no)
		(fp_line
			(start 0.7874 0.4064)
			(end 0.7874 -0.4064)
			(stroke
				(width 0.1524)
				(type default)
			)
			(layer "B.SilkS")
		)
		(fp_line
			(start 0.7874 -0.4064)
			(end -0.7874 -0.4064)
			(stroke
				(width 0.1524)
				(type default)
			)
			(layer "B.SilkS")
		)
		(fp_line
			(start -0.7874 0.4064)
			(end 0.7874 0.4064)
			(stroke
				(width 0.1524)
				(type default)
			)
			(layer "B.SilkS")
		)
		(fp_line
			(start -0.7874 -0.4064)
			(end -0.7874 0.4064)
			(stroke
				(width 0.1524)
				(type default)
			)
			(layer "B.SilkS")
		)
		(fp_line
			(start 0.67945 0.3048)
			(end 0.67945 -0.305054)
			(stroke
				(width 0.1)
				(type default)
			)
			(layer "B.Fab")
		)
		(fp_line
			(start 0.67945 -0.305054)
			(end 0.12065 -0.305054)
			(stroke
				(width 0.1)
				(type default)
			)
			(layer "B.Fab")
		)
		(fp_line
			(start 0.12065 0.3048)
			(end 0.67945 0.3048)
			(stroke
				(width 0.1)
				(type default)
			)
			(layer "B.Fab")
		)
		(fp_line
			(start 0.12065 0.2794)
			(end 0.12065 0.3048)
			(stroke
				(width 0.1)
				(type default)
			)
			(layer "B.Fab")
		)
		(fp_line
			(start 0.12065 -0.2794)
			(end -0.12065 -0.2794)
			(stroke
				(width 0.1)
				(type default)
			)
			(layer "B.Fab")
		)
		(fp_line
			(start 0.12065 -0.305054)
			(end 0.12065 -0.2794)
			(stroke
				(width 0.1)
				(type default)
			)
			(layer "B.Fab")
		)
		(fp_line
			(start -0.120396 0.3048)
			(end -0.120396 0.2794)
			(stroke
				(width 0.1)
				(type default)
			)
			(layer "B.Fab")
		)
		(fp_line
			(start -0.120396 0.2794)
			(end 0.12065 0.2794)
			(stroke
				(width 0.1)
				(type default)
			)
			(layer "B.Fab")
		)
		(fp_line
			(start -0.12065 -0.2794)
			(end -0.12065 -0.3048)
			(stroke
				(width 0.1)
				(type default)
			)
			(layer "B.Fab")
		)
		(fp_line
			(start -0.12065 -0.3048)
			(end -0.67945 -0.3048)
			(stroke
				(width 0.1)
				(type default)
			)
			(layer "B.Fab")
		)
		(fp_line
			(start -0.67945 0.3048)
			(end -0.120396 0.3048)
			(stroke
				(width 0.1)
				(type default)
			)
			(layer "B.Fab")
		)
		(fp_line
			(start -0.67945 -0.3048)
			(end -0.67945 0.3048)
			(stroke
				(width 0.1)
				(type default)
			)
			(layer "B.Fab")
		)
		(pad "1" smd circle
			(at 0.40005 0)
			(size 0 0)
			(layers "B.Cu" "B.Mask" "B.Paste")
			(net "PVDDCR_SOC_P0")
		)
		(pad "2" smd circle
			(at -0.40005 0)
			(size 0 0)
			(layers "B.Cu" "B.Mask" "B.Paste")
			(net "GND")
		)
	)
	(footprint ""
		(layer "B.Cu")
		(at 124.218446 -388.011162 -90)
		(property "Reference" "C447"
			(at 0 0 90)
			(layer "B.SilkS")
			(hide yes)
			(effects
				(font
					(size 1.27 1.27)
				)
				(justify mirror)
			)
		)
		(property "Value" ""
			(at 0 0 90)
			(layer "B.Fab")
			(effects
				(font
					(size 1.27 1.27)
				)
				(justify mirror)
			)
		)
		(duplicate_pad_numbers_are_jumpers no)
		(fp_line
			(start -0.299974 0.150114)
			(end 0.299974 0.150114)
			(stroke
				(width 0.1)
				(type default)
			)
			(layer "B.Fab")
		)
		(fp_line
			(start 0.299974 0.150114)
			(end 0.299974 -0.150114)
			(stroke
				(width 0.1)
				(type default)
			)
			(layer "B.Fab")
		)
		(fp_line
			(start -0.299974 -0.150114)
			(end -0.299974 0.150114)
			(stroke
				(width 0.1)
				(type default)
			)
			(layer "B.Fab")
		)
		(fp_line
			(start 0.299974 -0.150114)
			(end -0.299974 -0.150114)
			(stroke
				(width 0.1)
				(type default)
			)
			(layer "B.Fab")
		)
		(pad "1" smd rect
			(at 0.2667 0 90)
			(size 0.3048 0.381)
			(layers "B.Cu" "B.Mask" "B.Paste")
			(net "P1V8_CPU1_RT3_1A")
		)
		(pad "2" smd rect
			(at -0.2667 0 90)
			(size 0.3048 0.381)
			(layers "B.Cu" "B.Mask" "B.Paste")
			(net "GND")
		)
	)
	(footprint ""
		(layer "B.Cu")
		(at 358.796082 -257.744976 180)
		(property "Reference" "C3889"
			(at 0 0 0)
			(layer "B.SilkS")
			(hide yes)
			(effects
				(font
					(size 1.27 1.27)
				)
				(justify mirror)
			)
		)
		(property "Value" ""
			(at 0 0 0)
			(layer "B.Fab")
			(effects
				(font
					(size 1.27 1.27)
				)
				(justify mirror)
			)
		)
		(duplicate_pad_numbers_are_jumpers no)
		(fp_line
			(start 0.7874 0.4064)
			(end 0.7874 -0.4064)
			(stroke
				(width 0.1524)
				(type default)
			)
			(layer "B.SilkS")
		)
		(fp_line
			(start 0.7874 -0.4064)
			(end -0.7874 -0.4064)
			(stroke
				(width 0.1524)
				(type default)
			)
			(layer "B.SilkS")
		)
		(fp_line
			(start -0.7874 0.4064)
			(end 0.7874 0.4064)
			(stroke
				(width 0.1524)
				(type default)
			)
			(layer "B.SilkS")
		)
		(fp_line
			(start -0.7874 -0.4064)
			(end -0.7874 0.4064)
			(stroke
				(width 0.1524)
				(type default)
			)
			(layer "B.SilkS")
		)
		(fp_line
			(start 0.67945 0.3048)
			(end 0.67945 -0.305054)
			(stroke
				(width 0.1)
				(type default)
			)
			(layer "B.Fab")
		)
		(fp_line
			(start 0.67945 -0.305054)
			(end 0.12065 -0.305054)
			(stroke
				(width 0.1)
				(type default)
			)
			(layer "B.Fab")
		)
		(fp_line
			(start 0.12065 0.3048)
			(end 0.67945 0.3048)
			(stroke
				(width 0.1)
				(type default)
			)
			(layer "B.Fab")
		)
		(fp_line
			(start 0.12065 0.2794)
			(end 0.12065 0.3048)
			(stroke
				(width 0.1)
				(type default)
			)
			(layer "B.Fab")
		)
		(fp_line
			(start 0.12065 -0.2794)
			(end -0.12065 -0.2794)
			(stroke
				(width 0.1)
				(type default)
			)
			(layer "B.Fab")
		)
		(fp_line
			(start 0.12065 -0.305054)
			(end 0.12065 -0.2794)
			(stroke
				(width 0.1)
				(type default)
			)
			(layer "B.Fab")
		)
		(fp_line
			(start -0.120396 0.3048)
			(end -0.120396 0.2794)
			(stroke
				(width 0.1)
				(type default)
			)
			(layer "B.Fab")
		)
		(fp_line
			(start -0.120396 0.2794)
			(end 0.12065 0.2794)
			(stroke
				(width 0.1)
				(type default)
			)
			(layer "B.Fab")
		)
		(fp_line
			(start -0.12065 -0.2794)
			(end -0.12065 -0.3048)
			(stroke
				(width 0.1)
				(type default)
			)
			(layer "B.Fab")
		)
		(fp_line
			(start -0.12065 -0.3048)
			(end -0.67945 -0.3048)
			(stroke
				(width 0.1)
				(type default)
			)
			(layer "B.Fab")
		)
		(fp_line
			(start -0.67945 0.3048)
			(end -0.120396 0.3048)
			(stroke
				(width 0.1)
				(type default)
			)
			(layer "B.Fab")
		)
		(fp_line
			(start -0.67945 -0.3048)
			(end -0.67945 0.3048)
			(stroke
				(width 0.1)
				(type default)
			)
			(layer "B.Fab")
		)
		(pad "1" smd circle
			(at 0.40005 0)
			(size 0 0)
			(layers "B.Cu" "B.Mask" "B.Paste")
			(net "PVDDCR_SOC_P0")
		)
		(pad "2" smd circle
			(at -0.40005 0)
			(size 0 0)
			(layers "B.Cu" "B.Mask" "B.Paste")
			(net "GND")
		)
	)
)
